(kicad_pcb
	(version 20241229)
	(generator "pcbnew")
	(generator_version "9.0")
	(general
		(thickness 1.6296)
		(legacy_teardrops no)
	)
	(paper "A3")
	(title_block
		(title "Thunderbolt to 10GbE adapter")
		(date "2026-04-21")
		(rev "1.1.0")
		(company "Antmicro Ltd")
		(comment 1 "www.antmicro.com")
		(comment 9 "footprints 271-275 of 703")
	)
	(layers
		(0 "F.Cu" signal)
		(4 "In1.Cu" signal)
		(6 "In2.Cu" signal)
		(8 "In3.Cu" signal)
		(10 "In4.Cu" signal)
		(12 "In5.Cu" signal)
		(14 "In6.Cu" signal)
		(2 "B.Cu" signal)
		(9 "F.Adhes" user "F.Adhesive")
		(11 "B.Adhes" user "B.Adhesive")
		(13 "F.Paste" user)
		(15 "B.Paste" user)
		(5 "F.SilkS" user "F.Silkscreen")
		(7 "B.SilkS" user "B.Silkscreen")
		(1 "F.Mask" user)
		(3 "B.Mask" user)
		(17 "Dwgs.User" user "User.Drawings")
		(19 "Cmts.User" user "User.Comments")
		(21 "Eco1.User" user "User.Eco1")
		(23 "Eco2.User" user "User.Eco2")
		(25 "Edge.Cuts" user)
		(27 "Margin" user)
		(31 "F.CrtYd" user "F.Courtyard")
		(29 "B.CrtYd" user "B.Courtyard")
		(35 "F.Fab" user)
		(33 "B.Fab" user)
	)
	(footprint "antmicro-footprints:C_0402_1005Metric"
		(layer "F.Cu")
		(at 151.549999 111.15 180)
		(descr "Capacitor SMD 0402")
		(tags "capacitor SMD 0402")
		(property "Reference" "C131"
			(at -14.149998 -17.25 180)
			(layer "F.SilkS")
			(effects
				(font
					(size 0.7 0.7)
					(thickness 0.15)
				)
			)
		)
		(property "Value" "C_33p_0402"
			(at -1.022927 2.155213 180)
			(layer "F.Fab")
			(effects
				(font
					(size 0.7 0.7)
					(thickness 0.15)
				)
				(justify left bottom)
			)
		)
		(property "Datasheet" "https://spicat.kyocera-avx.com/product/mlcc/chartview/04025A330FAT2A/"
			(at 0 0 180)
			(layer "F.Fab")
			(hide yes)
			(effects
				(font
					(size 1.27 1.27)
					(thickness 0.15)
				)
			)
		)
		(property "Description" "SMD Multilayer Ceramic Capacitor, 33 pF, 50 V, 0402 [1005 Metric], ± 5%, C0G / NP0, MC"
			(at 0 0 180)
			(layer "F.Fab")
			(hide yes)
			(effects
				(font
					(size 1.27 1.27)
					(thickness 0.15)
				)
			)
		)
		(property "MPN" "04025A330FAT2A"
			(at 0 0 180)
			(unlocked yes)
			(layer "F.Fab")
			(hide yes)
			(effects
				(font
					(size 1 1)
					(thickness 0.15)
				)
			)
		)
		(property "Manufacturer" "KYOCERA AVX"
			(at 0 0 180)
			(unlocked yes)
			(layer "F.Fab")
			(hide yes)
			(effects
				(font
					(size 1 1)
					(thickness 0.15)
				)
			)
		)
		(property "License" "Apache-2.0"
			(at 0 0 180)
			(unlocked yes)
			(layer "F.Fab")
			(hide yes)
			(effects
				(font
					(size 1 1)
					(thickness 0.15)
				)
			)
		)
		(property "Author" "Antmicro"
			(at 0 0 180)
			(unlocked yes)
			(layer "F.Fab")
			(hide yes)
			(effects
				(font
					(size 1 1)
					(thickness 0.15)
				)
			)
		)
		(property "Val" "33p"
			(at 0 0 180)
			(unlocked yes)
			(layer "F.Fab")
			(hide yes)
			(effects
				(font
					(size 1 1)
					(thickness 0.15)
				)
			)
		)
		(property "Voltage" ""
			(at 0 0 180)
			(unlocked yes)
			(layer "F.Fab")
			(hide yes)
			(effects
				(font
					(size 1 1)
					(thickness 0.15)
				)
			)
		)
		(property "Dielectric" ""
			(at 0 0 180)
			(unlocked yes)
			(layer "F.Fab")
			(hide yes)
			(effects
				(font
					(size 1 1)
					(thickness 0.15)
				)
			)
		)
		(sheetname "/X710 DCDC converters/")
		(sheetfile "DCDC_converters_X710.kicad_sch")
		(attr smd dnp)
		(fp_rect
			(start -0.925 -0.47)
			(end 0.925 0.47)
			(stroke
				(width 0.05)
				(type default)
			)
			(fill no)
			(layer "F.CrtYd")
		)
		(fp_line
			(start 0.504 0.248)
			(end -0.494 0.248)
			(stroke
				(width 0.15)
				(type solid)
			)
			(layer "F.Fab")
		)
		(fp_line
			(start 0.504 -0.25)
			(end 0.504 0.248)
			(stroke
				(width 0.15)
				(type solid)
			)
			(layer "F.Fab")
		)
		(fp_line
			(start -0.494 0.248)
			(end -0.494 -0.25)
			(stroke
				(width 0.15)
				(type solid)
			)
			(layer "F.Fab")
		)
		(fp_line
			(start -0.494 -0.25)
			(end 0.504 -0.25)
			(stroke
				(width 0.15)
				(type solid)
			)
			(layer "F.Fab")
		)
		(fp_text user "${REFERENCE}"
			(at -0.939 4.599 180)
			(layer "F.Fab")
			(effects
				(font
					(size 0.7 0.7)
					(thickness 0.15)
				)
				(justify left bottom)
			)
		)
		(fp_text user "License: Apache-2.0"
			(at -0.939 5.799 180)
			(layer "F.Fab")
			(effects
				(font
					(size 0.7 0.7)
					(thickness 0.15)
				)
				(justify left bottom)
			)
		)
		(fp_text user "Author: Antmicro"
			(at -0.939 3.399 180)
			(layer "F.Fab")
			(effects
				(font
					(size 0.7 0.7)
					(thickness 0.15)
				)
				(justify left bottom)
			)
		)
		(pad "1" smd roundrect
			(at -0.48 0 180)
			(size 0.59 0.64)
			(layers "F.Cu" "F.Mask" "F.Paste")
			(roundrect_rratio 0.25)
			(net 337 "/X710 DCDC converters/1V88_FB")
			(pintype "passive")
		)
		(pad "2" smd roundrect
			(at 0.48 0 180)
			(size 0.59 0.64)
			(layers "F.Cu" "F.Mask" "F.Paste")
			(roundrect_rratio 0.25)
			(net 338 "/X710 DCDC converters/+1V88_OUT")
			(pintype "passive")
		)
	)
	(footprint "antmicro-footprints:C_0402_1005Metric"
		(layer "F.Cu")
		(at 138 80.75)
		(descr "Capacitor SMD 0402")
		(tags "capacitor SMD 0402")
		(property "Reference" "C273"
			(at -3.8 0.45 0)
			(layer "F.SilkS")
			(effects
				(font
					(size 0.7 0.7)
					(thickness 0.15)
				)
				(justify left bottom)
			)
		)
		(property "Value" "C_220n_16V_0402"
			(at -1.022927 2.155213 0)
			(layer "F.Fab")
			(effects
				(font
					(size 0.7 0.7)
					(thickness 0.15)
				)
				(justify left bottom)
			)
		)
		(property "Datasheet" "https://www.murata.com/products/productdetail?partno=GRM155R71C224KA12%23"
			(at 0 0 0)
			(layer "F.Fab")
			(hide yes)
			(effects
				(font
					(size 1.27 1.27)
					(thickness 0.15)
				)
			)
		)
		(property "Description" "SMD Multilayer Ceramic Capacitor, 0.22 µF, 16 V, 0402 [1005 Metric], ± 10%, X7R, GRM Series"
			(at 0 0 0)
			(layer "F.Fab")
			(hide yes)
			(effects
				(font
					(size 1.27 1.27)
					(thickness 0.15)
				)
			)
		)
		(property "MPN" "GRM155R71C224KA12D"
			(at 0 0 0)
			(unlocked yes)
			(layer "F.Fab")
			(hide yes)
			(effects
				(font
					(size 1 1)
					(thickness 0.15)
				)
			)
		)
		(property "Manufacturer" "Murata"
			(at 0 0 0)
			(unlocked yes)
			(layer "F.Fab")
			(hide yes)
			(effects
				(font
					(size 1 1)
					(thickness 0.15)
				)
			)
		)
		(property "License" "Apache-2.0"
			(at 0 0 0)
			(unlocked yes)
			(layer "F.Fab")
			(hide yes)
			(effects
				(font
					(size 1 1)
					(thickness 0.15)
				)
			)
		)
		(property "Author" "Antmicro"
			(at 0 0 0)
			(unlocked yes)
			(layer "F.Fab")
			(hide yes)
			(effects
				(font
					(size 1 1)
					(thickness 0.15)
				)
			)
		)
		(property "Val" "220n"
			(at 0 0 0)
			(unlocked yes)
			(layer "F.Fab")
			(hide yes)
			(effects
				(font
					(size 1 1)
					(thickness 0.15)
				)
			)
		)
		(property "Voltage" "16V"
			(at 0 0 0)
			(unlocked yes)
			(layer "F.Fab")
			(hide yes)
			(effects
				(font
					(size 1 1)
					(thickness 0.15)
				)
			)
		)
		(property "Dielectric" "X7R"
			(at 0 0 0)
			(unlocked yes)
			(layer "F.Fab")
			(hide yes)
			(effects
				(font
					(size 1 1)
					(thickness 0.15)
				)
			)
		)
		(sheetname "/X710-AT2 PCIe/")
		(sheetfile "x710-at2-pcie.kicad_sch")
		(attr smd)
		(fp_rect
			(start -0.925 -0.47)
			(end 0.925 0.47)
			(stroke
				(width 0.05)
				(type default)
			)
			(fill no)
			(layer "F.CrtYd")
		)
		(fp_line
			(start -0.494 -0.25)
			(end 0.504 -0.25)
			(stroke
				(width 0.15)
				(type solid)
			)
			(layer "F.Fab")
		)
		(fp_line
			(start -0.494 0.248)
			(end -0.494 -0.25)
			(stroke
				(width 0.15)
				(type solid)
			)
			(layer "F.Fab")
		)
		(fp_line
			(start 0.504 -0.25)
			(end 0.504 0.248)
			(stroke
				(width 0.15)
				(type solid)
			)
			(layer "F.Fab")
		)
		(fp_line
			(start 0.504 0.248)
			(end -0.494 0.248)
			(stroke
				(width 0.15)
				(type solid)
			)
			(layer "F.Fab")
		)
		(fp_text user "License: Apache-2.0"
			(at -0.939 5.799 0)
			(layer "F.Fab")
			(effects
				(font
					(size 0.7 0.7)
					(thickness 0.15)
				)
				(justify left bottom)
			)
		)
		(fp_text user "${REFERENCE}"
			(at -0.939 4.599 0)
			(layer "F.Fab")
			(effects
				(font
					(size 0.7 0.7)
					(thickness 0.15)
				)
				(justify left bottom)
			)
		)
		(fp_text user "Author: Antmicro"
			(at -0.939 3.399 0)
			(layer "F.Fab")
			(effects
				(font
					(size 0.7 0.7)
					(thickness 0.15)
				)
				(justify left bottom)
			)
		)
		(pad "1" smd roundrect
			(at -0.48 0)
			(size 0.59 0.64)
			(layers "F.Cu" "F.Mask" "F.Paste")
			(roundrect_rratio 0.25)
			(net 601 "/TB Controller/PCIex4.TX3+")
			(pintype "passive")
		)
		(pad "2" smd roundrect
			(at 0.48 0)
			(size 0.59 0.64)
			(layers "F.Cu" "F.Mask" "F.Paste")
			(roundrect_rratio 0.25)
			(net 33 "/X710-AT2 PCIe/PCIe_{x4}_AC.TX3+")
			(pintype "passive")
		)
	)
	(footprint "antmicro-footprints:R_0402_1005Metric"
		(layer "F.Cu")
		(at 119.25 65.5 180)
		(descr "Resistor SMD 0402")
		(tags "resistor SMD 0402")
		(property "Reference" "R132"
			(at -3.45 -1.4 180)
			(layer "F.SilkS")
			(effects
				(font
					(size 0.7 0.7)
					(thickness 0.15)
				)
				(justify left bottom)
			)
		)
		(property "Value" "R_10k_0402"
			(at -1.011843 1.772047 180)
			(layer "F.Fab")
			(effects
				(font
					(size 0.7 0.7)
					(thickness 0.15)
				)
				(justify left bottom)
			)
		)
		(property "Datasheet" "https://www.bourns.com/docs/product-datasheets/cr.pdf"
			(at 0 0 180)
			(layer "F.Fab")
			(hide yes)
			(effects
				(font
					(size 1.27 1.27)
					(thickness 0.15)
				)
			)
		)
		(property "Description" "SMD Chip Resistor, 10 kohm, ± 1%, 62.5 mW, 0402 [1005 Metric], Thick Film, General Purpose"
			(at 0 0 180)
			(layer "F.Fab")
			(hide yes)
			(effects
				(font
					(size 1.27 1.27)
					(thickness 0.15)
				)
			)
		)
		(property "MPN" "CR0402-FX-1002GLF"
			(at 0 0 180)
			(unlocked yes)
			(layer "F.Fab")
			(hide yes)
			(effects
				(font
					(size 1 1)
					(thickness 0.15)
				)
			)
		)
		(property "Manufacturer" "Bourns"
			(at 0 0 180)
			(unlocked yes)
			(layer "F.Fab")
			(hide yes)
			(effects
				(font
					(size 1 1)
					(thickness 0.15)
				)
			)
		)
		(property "License" "Apache-2.0"
			(at 0 0 180)
			(unlocked yes)
			(layer "F.Fab")
			(hide yes)
			(effects
				(font
					(size 1 1)
					(thickness 0.15)
				)
			)
		)
		(property "Author" "Antmicro"
			(at 0 0 180)
			(unlocked yes)
			(layer "F.Fab")
			(hide yes)
			(effects
				(font
					(size 1 1)
					(thickness 0.15)
				)
			)
		)
		(property "Val" "10k"
			(at 0 0 180)
			(unlocked yes)
			(layer "F.Fab")
			(hide yes)
			(effects
				(font
					(size 1 1)
					(thickness 0.15)
				)
			)
		)
		(property "Tolerance" "1%"
			(at 0 0 180)
			(unlocked yes)
			(layer "F.Fab")
			(hide yes)
			(effects
				(font
					(size 1 1)
					(thickness 0.15)
				)
			)
		)
		(sheetname "/X710-AT2 RSVD/")
		(sheetfile "x710-at2-rsvd.kicad_sch")
		(attr smd)
		(fp_rect
			(start -0.925 -0.47)
			(end 0.925 0.47)
			(stroke
				(width 0.05)
				(type default)
			)
			(fill no)
			(layer "F.CrtYd")
		)
		(fp_rect
			(start -0.5 -0.25)
			(end 0.5 0.25)
			(stroke
				(width 0.15)
				(type solid)
			)
			(fill no)
			(layer "F.Fab")
		)
		(fp_text user "Author: Antmicro"
			(at -0.95 4.169 180)
			(layer "F.Fab")
			(effects
				(font
					(size 0.7 0.7)
					(thickness 0.15)
				)
				(justify left bottom)
			)
		)
		(fp_text user "${REFERENCE}"
			(at -0.95 3.168 180)
			(layer "F.Fab")
			(effects
				(font
					(size 0.7 0.7)
					(thickness 0.15)
				)
				(justify left bottom)
			)
		)
		(fp_text user "License: Apache-2.0"
			(at -0.95 5.169 180)
			(layer "F.Fab")
			(effects
				(font
					(size 0.7 0.7)
					(thickness 0.15)
				)
				(justify left bottom)
			)
		)
		(pad "1" smd roundrect
			(at -0.48 0 180)
			(size 0.59 0.64)
			(layers "F.Cu" "F.Mask" "F.Paste")
			(roundrect_rratio 0.25)
			(net 23 "GND")
			(pintype "passive")
		)
		(pad "2" smd roundrect
			(at 0.48 0 180)
			(size 0.59 0.64)
			(layers "F.Cu" "F.Mask" "F.Paste")
			(roundrect_rratio 0.25)
			(net 89 "/X710-AT2 RSVD/DEBUG_Y20")
			(pintype "passive")
		)
	)
	(footprint "antmicro-footprints:R_0402_1005Metric"
		(layer "F.Cu")
		(at 164 76.4 180)
		(descr "Resistor SMD 0402")
		(tags "resistor SMD 0402")
		(property "Reference" "R196"
			(at 1 -6.4 180)
			(layer "F.SilkS")
			(effects
				(font
					(size 0.7 0.7)
					(thickness 0.15)
				)
				(justify left bottom)
			)
		)
		(property "Value" "R_0R_0402"
			(at -1.011843 1.772047 180)
			(layer "F.Fab")
			(effects
				(font
					(size 0.7 0.7)
					(thickness 0.15)
				)
				(justify left bottom)
			)
		)
		(property "Datasheet" "https://industrial.panasonic.com/cdbs/www-data/pdf/RDA0000/AOA0000C301.pdf"
			(at 0 0 180)
			(layer "F.Fab")
			(hide yes)
			(effects
				(font
					(size 1.27 1.27)
					(thickness 0.15)
				)
			)
		)
		(property "Description" "SMD Chip Resistor, Jumper, 0 ohm, 100 mW, 0402 [1005 Metric], Thick Film, General Purpose"
			(at 0 0 180)
			(layer "F.Fab")
			(hide yes)
			(effects
				(font
					(size 1.27 1.27)
					(thickness 0.15)
				)
			)
		)
		(property "MPN" "ERJ2GE0R00X"
			(at 0 0 180)
			(unlocked yes)
			(layer "F.Fab")
			(hide yes)
			(effects
				(font
					(size 1 1)
					(thickness 0.15)
				)
			)
		)
		(property "Manufacturer" "Panasonic"
			(at 0 0 180)
			(unlocked yes)
			(layer "F.Fab")
			(hide yes)
			(effects
				(font
					(size 1 1)
					(thickness 0.15)
				)
			)
		)
		(property "License" "Apache-2.0"
			(at 0 0 180)
			(unlocked yes)
			(layer "F.Fab")
			(hide yes)
			(effects
				(font
					(size 1 1)
					(thickness 0.15)
				)
			)
		)
		(property "Author" "Antmicro"
			(at 0 0 180)
			(unlocked yes)
			(layer "F.Fab")
			(hide yes)
			(effects
				(font
					(size 1 1)
					(thickness 0.15)
				)
			)
		)
		(property "Val" "0R"
			(at 0 0 180)
			(unlocked yes)
			(layer "F.Fab")
			(hide yes)
			(effects
				(font
					(size 1 1)
					(thickness 0.15)
				)
			)
		)
		(property "Tolerance" "~"
			(at 0 0 180)
			(unlocked yes)
			(layer "F.Fab")
			(hide yes)
			(effects
				(font
					(size 1 1)
					(thickness 0.15)
				)
			)
		)
		(property "Current" "1A"
			(at 0 0 180)
			(unlocked yes)
			(layer "F.Fab")
			(hide yes)
			(effects
				(font
					(size 1 1)
					(thickness 0.15)
				)
			)
		)
		(sheetname "/X710-AT2 10GbE/")
		(sheetfile "x710-at2-10gbe.kicad_sch")
		(attr smd)
		(fp_rect
			(start -0.925 -0.47)
			(end 0.925 0.47)
			(stroke
				(width 0.05)
				(type default)
			)
			(fill no)
			(layer "F.CrtYd")
		)
		(fp_rect
			(start -0.5 -0.25)
			(end 0.5 0.25)
			(stroke
				(width 0.15)
				(type solid)
			)
			(fill no)
			(layer "F.Fab")
		)
		(fp_text user "License: Apache-2.0"
			(at -0.95 5.169 180)
			(layer "F.Fab")
			(effects
				(font
					(size 0.7 0.7)
					(thickness 0.15)
				)
				(justify left bottom)
			)
		)
		(fp_text user "Author: Antmicro"
			(at -0.95 4.169 180)
			(layer "F.Fab")
			(effects
				(font
					(size 0.7 0.7)
					(thickness 0.15)
				)
				(justify left bottom)
			)
		)
		(fp_text user "${REFERENCE}"
			(at -0.95 3.168 180)
			(layer "F.Fab")
			(effects
				(font
					(size 0.7 0.7)
					(thickness 0.15)
				)
				(justify left bottom)
			)
		)
		(pad "1" smd roundrect
			(at -0.48 0 180)
			(size 0.59 0.64)
			(layers "F.Cu" "F.Mask" "F.Paste")
			(roundrect_rratio 0.25)
			(net 146 "/X710-AT2 10GbE/~{PHY_RESET_3V3}")
			(pintype "passive")
		)
		(pad "2" smd roundrect
			(at 0.48 0 180)
			(size 0.59 0.64)
			(layers "F.Cu" "F.Mask" "F.Paste")
			(roundrect_rratio 0.25)
			(net 110 "/X710-AT2 10GbE/~{PHY_RESET_3V3_R}")
			(pintype "passive")
		)
	)
	(footprint "antmicro-footprints:R_0402_1005Metric"
		(layer "F.Cu")
		(at 159.249997 112.150001)
		(descr "Resistor SMD 0402")
		(tags "resistor SMD 0402")
		(property "Reference" "R105"
			(at 12.950004 17.25 0)
			(layer "F.SilkS")
			(effects
				(font
					(size 0.7 0.7)
					(thickness 0.15)
				)
			)
		)
		(property "Value" "R_30k_0402"
			(at -1.011843 1.772047 0)
			(layer "F.Fab")
			(effects
				(font
					(size 0.7 0.7)
					(thickness 0.15)
				)
				(justify left bottom)
			)
		)
		(property "Datasheet" "https://www.bourns.com/docs/product-datasheets/cr.pdf"
			(at 0 0 0)
			(layer "F.Fab")
			(hide yes)
			(effects
				(font
					(size 1.27 1.27)
					(thickness 0.15)
				)
			)
		)
		(property "Description" "SMD Chip Resistor, 30 kohm, ± 1%, 63 mW, 0402 [1005 Metric], Thick Film, General Purpose"
			(at 0 0 0)
			(layer "F.Fab")
			(hide yes)
			(effects
				(font
					(size 1.27 1.27)
					(thickness 0.15)
				)
			)
		)
		(property "MPN" "CR0402-FX-3002GLF"
			(at 0 0 0)
			(unlocked yes)
			(layer "F.Fab")
			(hide yes)
			(effects
				(font
					(size 1 1)
					(thickness 0.15)
				)
			)
		)
		(property "Manufacturer" "Bourns"
			(at 0 0 0)
			(unlocked yes)
			(layer "F.Fab")
			(hide yes)
			(effects
				(font
					(size 1 1)
					(thickness 0.15)
				)
			)
		)
		(property "License" "Apache-2.0"
			(at 0 0 0)
			(unlocked yes)
			(layer "F.Fab")
			(hide yes)
			(effects
				(font
					(size 1 1)
					(thickness 0.15)
				)
			)
		)
		(property "Author" "Antmicro"
			(at 0 0 0)
			(unlocked yes)
			(layer "F.Fab")
			(hide yes)
			(effects
				(font
					(size 1 1)
					(thickness 0.15)
				)
			)
		)
		(property "Val" "30k"
			(at 0 0 0)
			(unlocked yes)
			(layer "F.Fab")
			(hide yes)
			(effects
				(font
					(size 1 1)
					(thickness 0.15)
				)
			)
		)
		(property "Tolerance" "1%"
			(at 0 0 0)
			(unlocked yes)
			(layer "F.Fab")
			(hide yes)
			(effects
				(font
					(size 1 1)
					(thickness 0.15)
				)
			)
		)
		(sheetname "/X710 DCDC converters/")
		(sheetfile "DCDC_converters_X710.kicad_sch")
		(attr smd)
		(fp_rect
			(start -0.925 -0.47)
			(end 0.925 0.47)
			(stroke
				(width 0.05)
				(type default)
			)
			(fill no)
			(layer "F.CrtYd")
		)
		(fp_rect
			(start -0.5 -0.25)
			(end 0.5 0.25)
			(stroke
				(width 0.15)
				(type solid)
			)
			(fill no)
			(layer "F.Fab")
		)
		(fp_text user "Author: Antmicro"
			(at -0.95 4.169 0)
			(layer "F.Fab")
			(effects
				(font
					(size 0.7 0.7)
					(thickness 0.15)
				)
				(justify left bottom)
			)
		)
		(fp_text user "License: Apache-2.0"
			(at -0.95 5.169 0)
			(layer "F.Fab")
			(effects
				(font
					(size 0.7 0.7)
					(thickness 0.15)
				)
				(justify left bottom)
			)
		)
		(fp_text user "${REFERENCE}"
			(at -0.95 3.168 0)
			(layer "F.Fab")
			(effects
				(font
					(size 0.7 0.7)
					(thickness 0.15)
				)
				(justify left bottom)
			)
		)
		(pad "1" smd roundrect
			(at -0.48 0)
			(size 0.59 0.64)
			(layers "F.Cu" "F.Mask" "F.Paste")
			(roundrect_rratio 0.25)
			(net 23 "GND")
			(pintype "passive")
		)
		(pad "2" smd roundrect
			(at 0.48 0)
			(size 0.59 0.64)
			(layers "F.Cu" "F.Mask" "F.Paste")
			(roundrect_rratio 0.25)
			(net 340 "/X710 DCDC converters/1V0_FB")
			(pintype "passive")
		)
	)
)
